# Bryce Canyon_IOM_IOC_Stackup.xlsx — PCB Test Plan_HVM(90+) (pcb-stackup)
|  | Board vendor give feedback of quantity in yellow columns based on the AQL table or description. |  |  |  |  |  |  |  |  |  |  |  |  |  |  |
|  | Wiwynn PM give feedback in blue columns |  |  |  |  |  |  |  |  |  |  |  |  |  |  |
| Person to be informed : PCB vendor, EE, SI, PM, PSM, Buyer, SQM |  |  |  |  |  |  |  |  |  |  |  |  |  |  |  |
| Simple flow : SI (test requirements) -> PM/AM (Total PCBS demand) -> Buyer -> Board Vendor (yellow column feedback) -> Buyer -> Person to be informed (Check and Track) |  |  |  |  |  |  |  |  |  |  |  |  |  |  |  |
| PO(purchase order) : If there are many POs for this PCB, 1st sample quantity is based on 1st PO, 2nd sample quantity is based on 2nd PO. |  |  |  |  |  |  |  |  |  |  |  |  |  |  |  |
| Project Name | PCB name | PCB# (1XXXX-XX) | Product Stage | Batch# | PCB Vendor | Production  Lot size | PCBs Demand | Delta-L Coupon (PCB Vendor) | Delta-L Coupon (3rd Party Lab) | Impedance Coupon (PCB Vendor) | In-board trace correlation (PCB Vendor) | X-section Analysis (PCB Vendor) | IST (3rd Party Lab) | IPC-6012D (3rd Party Lab) | Note |
| Bryce Canyon | IOM IOC | 16318-2 | HVM(90+ days) | N/A |  |  | TBD | No | No | Yes | No | No | No | No | Need Test? (Yes, No) |
| Tracking Code On Both Of Coupon And PCB |  |  |  |  |  |  |  |  |  | N/A |  |  |  |  |  |
| Test Item Acceptance Criteria |  |  |  |  |  |  |  |  |  | c = 0 |  |  |  |  |  |
| Test Item Sampling Quantity |  |  |  |  |  |  |  |  |  | Mil-STD 105E single sampling plan, AQL 0.65, level 2 |  |  |  |  |  |
| Test Time (working days) |  |  |  |  |  |  |  |  |  |  |  |  |  |  |  |
| Test Item Shipping Quantity |  |  |  |  |  |  |  |  |  |  |  |  |  |  |  |
| Shipping Address |  |  |  |  |  |  |  |  |  |  |  |  |  |  |  |
| Receiver Name |  |  |  |  |  |  |  |  |  |  |  |  |  |  |  |
| Receiver Phone# |  |  |  |  |  |  |  |  |  |  |  |  |  |  |  |
